# T6G (Grand Teton) — schematic netlist excerpt (pin names and nets, part order shuffled) for the footprints in the layout excerpt that follows; sources: Cadence DE-HDL packaged netlist, KiCad conversion of 04192023_DAF0TMB3IC0_F0TG_MB_C_brd_V02_OCP.brd

C911  Q_CAP_DIFFBUS  DIFF BUS_0.22UF 6.3V 20% X6S  pkg C0201  page 63 : \1\ = P5E_CPU0_P0_TX_C_DP<11> ; \2\ = P5E_CPU0_P0_TX_DP<11>
R6031  Q_RES  33 5% CHIP  pkg 0402LF  page 80 : A = VIRTUAL_RESEAT_FPGA_N ; B = VIRTUAL_RESEAT_FPGA_R_N
PC323_1  Q_CAP  1UF 25V 10% X6S  pkg C0402  page 215 : A = SW_P12V_AUX_PVDDCR_SOC_P1_FLT ; B = GND

(kicad_pcb
	(version 20260206)
	(generator "pcbnew")
	(generator_version "10.0")
	(general
		(thickness 1.6)
		(legacy_teardrops no)
	)
	(paper "A4")
	(title_block
		(title "04192023_DAF0TMB3IC0_F0TG_MB_C_brd_V02_OCP.brd")
		(comment 1 "Grand Teton / footprints 554-556 of 8354")
	)
	(layers
		(0 "F.Cu" signal "TOP")
		(4 "In1.Cu" signal "GND")
		(6 "In2.Cu" signal "IN1")
		(8 "In3.Cu" signal "GND1")
		(10 "In4.Cu" signal "IN2")
		(12 "In5.Cu" signal "GND2")
		(14 "In6.Cu" signal "IN3")
		(16 "In7.Cu" signal "GND3")
		(18 "In8.Cu" signal "VCC")
		(20 "In9.Cu" signal "VCC1")
		(22 "In10.Cu" signal "GND4")
		(24 "In11.Cu" signal "IN4")
		(26 "In12.Cu" signal "GND5")
		(28 "In13.Cu" signal "IN5")
		(30 "In14.Cu" signal "GND6")
		(32 "In15.Cu" signal "IN6")
		(34 "In16.Cu" signal "GND7")
		(2 "B.Cu" signal "BOTTOM")
		(9 "F.Adhes" user "F.Adhesive")
		(11 "B.Adhes" user "B.Adhesive")
		(13 "F.Paste" user "Package Geometry/Pastemask Top")
		(15 "B.Paste" user "Package Geometry/Pastemask Bottom")
		(5 "F.SilkS" user "Ref Des/Silkscreen Top")
		(7 "B.SilkS" user "Ref Des/Silkscreen Bottom")
		(1 "F.Mask" user "Board Geometry/Soldermask Top")
		(3 "B.Mask" user "Board Geometry/Soldermask Bottom")
		(17 "Dwgs.User" user "User.Drawings")
		(19 "Cmts.User" user "User.Comments")
		(21 "Eco1.User" user "User.Eco1")
		(23 "Eco2.User" user "User.Eco2")
		(25 "Edge.Cuts" user "Board Geometry/Outline")
		(27 "Margin" user)
		(31 "F.CrtYd" user "Package Geometry/Place Bound Top")
		(29 "B.CrtYd" user "Package Geometry/Place Bound Bottom")
		(35 "F.Fab" user "Ref Des/Assembly Top")
		(33 "B.Fab" user "Ref Des/Assembly Bottom")
	)
	(footprint ""
		(layer "F.Cu")
		(at 163.743894 -120.37187)
		(property "Reference" "R6031"
			(at 0 0 0)
			(layer "F.SilkS")
			(hide yes)
			(effects
				(font
					(size 1.27 1.27)
				)
			)
		)
		(property "Value" ""
			(at 0 0 0)
			(layer "F.Fab")
			(effects
				(font
					(size 1.27 1.27)
				)
			)
		)
		(duplicate_pad_numbers_are_jumpers no)
		(fp_line
			(start -0.7874 -0.4064)
			(end 0.7874 -0.4064)
			(stroke
				(width 0.1524)
				(type default)
			)
			(layer "F.SilkS")
		)
		(fp_line
			(start -0.7874 0.4064)
			(end -0.7874 -0.4064)
			(stroke
				(width 0.1524)
				(type default)
			)
			(layer "F.SilkS")
		)
		(fp_line
			(start 0.7874 -0.4064)
			(end 0.7874 0.4064)
			(stroke
				(width 0.1524)
				(type default)
			)
			(layer "F.SilkS")
		)
		(fp_line
			(start 0.7874 0.4064)
			(end -0.7874 0.4064)
			(stroke
				(width 0.1524)
				(type default)
			)
			(layer "F.SilkS")
		)
		(fp_line
			(start -0.67945 -0.305054)
			(end -0.12065 -0.305054)
			(stroke
				(width 0.1)
				(type default)
			)
			(layer "F.Fab")
		)
		(fp_line
			(start -0.67945 0.3048)
			(end -0.67945 -0.305054)
			(stroke
				(width 0.1)
				(type default)
			)
			(layer "F.Fab")
		)
		(fp_line
			(start -0.12065 -0.305054)
			(end -0.12065 -0.2794)
			(stroke
				(width 0.1)
				(type default)
			)
			(layer "F.Fab")
		)
		(fp_line
			(start -0.12065 -0.2794)
			(end 0.12065 -0.2794)
			(stroke
				(width 0.1)
				(type default)
			)
			(layer "F.Fab")
		)
		(fp_line
			(start -0.12065 0.2794)
			(end -0.12065 0.3048)
			(stroke
				(width 0.1)
				(type default)
			)
			(layer "F.Fab")
		)
		(fp_line
			(start -0.12065 0.3048)
			(end -0.67945 0.3048)
			(stroke
				(width 0.1)
				(type default)
			)
			(layer "F.Fab")
		)
		(fp_line
			(start 0.120396 0.2794)
			(end -0.12065 0.2794)
			(stroke
				(width 0.1)
				(type default)
			)
			(layer "F.Fab")
		)
		(fp_line
			(start 0.120396 0.3048)
			(end 0.120396 0.2794)
			(stroke
				(width 0.1)
				(type default)
			)
			(layer "F.Fab")
		)
		(fp_line
			(start 0.12065 -0.3048)
			(end 0.67945 -0.3048)
			(stroke
				(width 0.1)
				(type default)
			)
			(layer "F.Fab")
		)
		(fp_line
			(start 0.12065 -0.2794)
			(end 0.12065 -0.3048)
			(stroke
				(width 0.1)
				(type default)
			)
			(layer "F.Fab")
		)
		(fp_line
			(start 0.67945 -0.3048)
			(end 0.67945 0.3048)
			(stroke
				(width 0.1)
				(type default)
			)
			(layer "F.Fab")
		)
		(fp_line
			(start 0.67945 0.3048)
			(end 0.120396 0.3048)
			(stroke
				(width 0.1)
				(type default)
			)
			(layer "F.Fab")
		)
		(pad "1" smd circle
			(at -0.40005 0)
			(size 0 0)
			(layers "F.Cu" "F.Mask" "F.Paste")
			(net "VIRTUAL_RESEAT_FPGA_N")
		)
		(pad "2" smd circle
			(at 0.40005 0)
			(size 0 0)
			(layers "F.Cu" "F.Mask" "F.Paste")
			(net "VIRTUAL_RESEAT_FPGA_R_N")
		)
	)
	(footprint ""
		(layer "F.Cu")
		(at 319.411096 -381.41783 -90)
		(property "Reference" "C911"
			(at 0 0 270)
			(layer "F.SilkS")
			(hide yes)
			(effects
				(font
					(size 1.27 1.27)
				)
			)
		)
		(property "Value" ""
			(at 0 0 270)
			(layer "F.Fab")
			(effects
				(font
					(size 1.27 1.27)
				)
			)
		)
		(duplicate_pad_numbers_are_jumpers no)
		(fp_line
			(start -0.299974 0.150114)
			(end -0.299974 -0.150114)
			(stroke
				(width 0.1)
				(type default)
			)
			(layer "F.Fab")
		)
		(fp_line
			(start 0.299974 0.150114)
			(end -0.299974 0.150114)
			(stroke
				(width 0.1)
				(type default)
			)
			(layer "F.Fab")
		)
		(fp_line
			(start -0.299974 -0.150114)
			(end 0.299974 -0.150114)
			(stroke
				(width 0.1)
				(type default)
			)
			(layer "F.Fab")
		)
		(fp_line
			(start 0.299974 -0.150114)
			(end 0.299974 0.150114)
			(stroke
				(width 0.1)
				(type default)
			)
			(layer "F.Fab")
		)
		(pad "1" smd rect
			(at -0.2667 0 270)
			(size 0.3048 0.381)
			(layers "F.Cu" "F.Mask" "F.Paste")
			(net "P5E_CPU0_P0_TX_C_DP<11>")
		)
		(pad "2" smd rect
			(at 0.2667 0 270)
			(size 0.3048 0.381)
			(layers "F.Cu" "F.Mask" "F.Paste")
			(net "P5E_CPU0_P0_TX_DP<11>")
		)
	)
	(footprint ""
		(layer "F.Cu")
		(at 112.048798 -171.808902 90)
		(property "Reference" "PC323_1"
			(at 0 0 90)
			(layer "F.SilkS")
			(hide yes)
			(effects
				(font
					(size 1.27 1.27)
				)
			)
		)
		(property "Value" ""
			(at 0 0 90)
			(layer "F.Fab")
			(effects
				(font
					(size 1.27 1.27)
				)
			)
		)
		(duplicate_pad_numbers_are_jumpers no)
		(fp_line
			(start 0.7874 -0.4064)
			(end 0.7874 0.4064)
			(stroke
				(width 0.1524)
				(type default)
			)
			(layer "F.SilkS")
		)
		(fp_line
			(start -0.7874 -0.4064)
			(end 0.7874 -0.4064)
			(stroke
				(width 0.1524)
				(type default)
			)
			(layer "F.SilkS")
		)
		(fp_line
			(start 0.7874 0.4064)
			(end -0.7874 0.4064)
			(stroke
				(width 0.1524)
				(type default)
			)
			(layer "F.SilkS")
		)
		(fp_line
			(start -0.7874 0.4064)
			(end -0.7874 -0.4064)
			(stroke
				(width 0.1524)
				(type default)
			)
			(layer "F.SilkS")
		)
		(fp_line
			(start -0.12065 -0.305054)
			(end -0.12065 -0.2794)
			(stroke
				(width 0.1)
				(type default)
			)
			(layer "F.Fab")
		)
		(fp_line
			(start -0.67945 -0.305054)
			(end -0.12065 -0.305054)
			(stroke
				(width 0.1)
				(type default)
			)
			(layer "F.Fab")
		)
		(fp_line
			(start 0.67945 -0.3048)
			(end 0.67945 0.3048)
			(stroke
				(width 0.1)
				(type default)
			)
			(layer "F.Fab")
		)
		(fp_line
			(start 0.12065 -0.3048)
			(end 0.67945 -0.3048)
			(stroke
				(width 0.1)
				(type default)
			)
			(layer "F.Fab")
		)
		(fp_line
			(start 0.12065 -0.2794)
			(end 0.12065 -0.3048)
			(stroke
				(width 0.1)
				(type default)
			)
			(layer "F.Fab")
		)
		(fp_line
			(start -0.12065 -0.2794)
			(end 0.12065 -0.2794)
			(stroke
				(width 0.1)
				(type default)
			)
			(layer "F.Fab")
		)
		(fp_line
			(start 0.120396 0.2794)
			(end -0.12065 0.2794)
			(stroke
				(width 0.1)
				(type default)
			)
			(layer "F.Fab")
		)
		(fp_line
			(start -0.12065 0.2794)
			(end -0.12065 0.3048)
			(stroke
				(width 0.1)
				(type default)
			)
			(layer "F.Fab")
		)
		(fp_line
			(start 0.67945 0.3048)
			(end 0.120396 0.3048)
			(stroke
				(width 0.1)
				(type default)
			)
			(layer "F.Fab")
		)
		(fp_line
			(start 0.120396 0.3048)
			(end 0.120396 0.2794)
			(stroke
				(width 0.1)
				(type default)
			)
			(layer "F.Fab")
		)
		(fp_line
			(start -0.12065 0.3048)
			(end -0.67945 0.3048)
			(stroke
				(width 0.1)
				(type default)
			)
			(layer "F.Fab")
		)
		(fp_line
			(start -0.67945 0.3048)
			(end -0.67945 -0.305054)
			(stroke
				(width 0.1)
				(type default)
			)
			(layer "F.Fab")
		)
		(pad "1" smd circle
			(at -0.40005 0 90)
			(size 0 0)
			(layers "F.Cu" "F.Mask" "F.Paste")
			(net "SW_P12V_AUX_PVDDCR_SOC_P1_FLT")
		)
		(pad "2" smd circle
			(at 0.40005 0 90)
			(size 0 0)
			(layers "F.Cu" "F.Mask" "F.Paste")
			(net "GND")
		)
	)
)
